G04 ================== begin FILE IDENTIFICATION RECORD ==================*
G04 Layout Name:  15750-1.brd*
G04 Film Name:    DP_REF_L6*
G04 File Format:  Gerber RS274X*
G04 File Origin:  Cadence Allegro 16.5-S056*
G04 Origin Date:  Fri Dec 30 13:21:45 2016*
G04 *
G04 Layer:  BOARD GEOMETRY/DP_REF_L6_TBL*
G04 Layer:  BOARD GEOMETRY/DP_REF_L6_L6*
G04 Layer:  BOARD GEOMETRY/PANEL_OUTLINE*
G04 *
G04 Offset:    (0.00 0.00)*
G04 Mirror:    No*
G04 Mode:      Positive*
G04 Rotation:  0*
G04 FullContactRelief:  No*
G04 UndefLineWidth:     6.00*
G04 ================== end FILE IDENTIFICATION RECORD ====================*
%FSLAX35Y35*MOIN*%
%IR0*IPPOS*OFA0.00000B0.00000*MIA0B0*SFA1.00000B1.00000*%
%ADD10C,.02*%
%ADD11C,.006*%
%ADD12C,.00525*%
G75*
%LPD*%
G75*
G54D10*
G01X772440Y279160D02*
X1577440D01*
G01X772440Y348460D02*
Y279160D01*
G01Y313810D02*
X1577440D01*
G01X772440Y348460D02*
X1577440D01*
G01X947440D02*
Y279160D01*
G01X1262440Y348460D02*
Y279160D01*
G01X1367440Y348460D02*
Y279160D01*
G01X1577440Y348460D02*
Y279160D01*
G54D11*
G01X6549Y-157539D02*
Y-175039D01*
G01X1527Y-157539D02*
X11571D01*
G01X20337Y-175039D02*
Y-157539D01*
G01Y-165997D02*
X21429Y-164539D01*
X22521Y-163664D01*
X24267Y-163373D01*
X25577Y-163664D01*
X27106Y-164831D01*
X27761Y-166581D01*
Y-175039D01*
G01X41549Y-163373D02*
Y-175039D01*
G01Y-158706D02*
X41112Y-158414D01*
Y-157831D01*
X41549Y-157539D01*
X41986Y-157831D01*
Y-158414D01*
X41549Y-158706D01*
G01X55774Y-172998D02*
X56866Y-174164D01*
X58394Y-175039D01*
X59704D01*
X61014Y-174456D01*
X61887Y-173581D01*
X62324Y-172415D01*
X62106Y-170664D01*
X61232Y-169789D01*
X57302Y-168039D01*
X56429Y-165997D01*
X56866Y-164539D01*
X57739Y-163664D01*
X59049Y-163373D01*
X60359Y-163664D01*
X61669Y-164539D01*
G01X90992Y-179414D02*
X92521Y-180581D01*
X94267Y-180872D01*
X95795Y-180581D01*
X97106Y-179123D01*
X97979Y-177081D01*
Y-163373D01*
G01Y-165706D02*
X97106Y-164539D01*
X95795Y-163664D01*
X94267Y-163373D01*
X92521Y-163956D01*
X91429Y-165122D01*
X90555Y-167164D01*
X90119Y-169206D01*
X90337Y-170956D01*
X91211Y-172998D01*
X92521Y-174456D01*
X94267Y-175039D01*
X95577Y-174747D01*
X97106Y-173581D01*
X97979Y-172415D01*
G01X108274Y-167164D02*
X115261D01*
X114606Y-165122D01*
X113514Y-163956D01*
X111986Y-163373D01*
X110457Y-163664D01*
X109147Y-164539D01*
X108274Y-166581D01*
X107837Y-168331D01*
Y-170081D01*
X108274Y-171831D01*
X109366Y-173581D01*
X110676Y-174747D01*
X112204Y-175039D01*
X113732Y-174456D01*
X115261Y-172706D01*
G01X125992Y-175039D02*
Y-163373D01*
G01Y-165706D02*
X127084Y-164539D01*
X128176Y-163664D01*
X129704Y-163373D01*
X130795Y-163664D01*
X132106Y-164539D01*
G01X142619Y-175039D02*
Y-157539D01*
G01Y-166289D02*
X143711Y-164539D01*
X145021Y-163664D01*
X146331Y-163373D01*
X148295Y-163956D01*
X149606Y-165122D01*
X150479Y-167164D01*
Y-169497D01*
X150042Y-171831D01*
X149169Y-173581D01*
X147641Y-174747D01*
X146331Y-175039D01*
X145021Y-174747D01*
X143711Y-173873D01*
X142619Y-172415D01*
G01X160774Y-167164D02*
X167761D01*
X167106Y-165122D01*
X166014Y-163956D01*
X164486Y-163373D01*
X162957Y-163664D01*
X161647Y-164539D01*
X160774Y-166581D01*
X160337Y-168331D01*
Y-170081D01*
X160774Y-171831D01*
X161866Y-173581D01*
X163176Y-174747D01*
X164704Y-175039D01*
X166232Y-174456D01*
X167761Y-172706D01*
G01X178492Y-175039D02*
Y-163373D01*
G01Y-165706D02*
X179584Y-164539D01*
X180676Y-163664D01*
X182204Y-163373D01*
X183295Y-163664D01*
X184606Y-164539D01*
G01X216549Y-163373D02*
Y-175039D01*
G01Y-158706D02*
X216112Y-158414D01*
Y-157831D01*
X216549Y-157539D01*
X216986Y-157831D01*
Y-158414D01*
X216549Y-158706D01*
G01X230774Y-172998D02*
X231866Y-174164D01*
X233394Y-175039D01*
X234704D01*
X236014Y-174456D01*
X236887Y-173581D01*
X237324Y-172415D01*
X237106Y-170664D01*
X236232Y-169789D01*
X232302Y-168039D01*
X231429Y-165997D01*
X231866Y-164539D01*
X232739Y-163664D01*
X234049Y-163373D01*
X235359Y-163664D01*
X236669Y-164539D01*
G01X265555Y-179414D02*
X267084Y-180581D01*
X268394Y-180872D01*
X270141Y-180289D01*
X271451Y-178831D01*
X272106Y-176205D01*
Y-163373D01*
G01Y-158706D02*
X271669Y-158414D01*
Y-157831D01*
X272106Y-157539D01*
X272542Y-157831D01*
Y-158414D01*
X272106Y-158706D01*
G01X282837Y-163373D02*
Y-171539D01*
X283711Y-173581D01*
X285021Y-174747D01*
X286549Y-175039D01*
X288077Y-174747D01*
X289387Y-173581D01*
X290261Y-171539D01*
G01Y-175039D02*
Y-163373D01*
G01X300774Y-172998D02*
X301866Y-174164D01*
X303394Y-175039D01*
X304704D01*
X306014Y-174456D01*
X306887Y-173581D01*
X307324Y-172415D01*
X307106Y-170664D01*
X306232Y-169789D01*
X302302Y-168039D01*
X301429Y-165997D01*
X301866Y-164539D01*
X302739Y-163664D01*
X304049Y-163373D01*
X305359Y-163664D01*
X306669Y-164539D01*
G01X321549Y-157539D02*
Y-175039D01*
G01X318492Y-163373D02*
X324606D01*
G01X355239Y-175039D02*
Y-160164D01*
X355676Y-158706D01*
X356549Y-157831D01*
X357859Y-157539D01*
X359169Y-158122D01*
X359824Y-159581D01*
G01X357204Y-164539D02*
X352837D01*
G01X374049Y-175039D02*
X372739Y-174747D01*
X371429Y-173581D01*
X370555Y-171539D01*
X370119Y-169206D01*
X370555Y-166872D01*
X371429Y-164831D01*
X372739Y-163664D01*
X374049Y-163373D01*
X375359Y-163664D01*
X376669Y-164831D01*
X377542Y-166872D01*
X377761Y-169206D01*
X377542Y-171539D01*
X376669Y-173581D01*
X375359Y-174747D01*
X374049Y-175039D01*
G01X388492D02*
Y-163373D01*
G01Y-165706D02*
X389584Y-164539D01*
X390676Y-163664D01*
X392204Y-163373D01*
X393295Y-163664D01*
X394606Y-164539D01*
G01X421964Y-180289D02*
X423274Y-180872D01*
X425021Y-180289D01*
X426112Y-179123D01*
X426986Y-177664D01*
X428295Y-172998D01*
X431134Y-163373D01*
G01X424147D02*
X428295Y-172998D01*
G01X444049Y-175039D02*
X442739Y-174747D01*
X441429Y-173581D01*
X440555Y-171539D01*
X440119Y-169206D01*
X440555Y-166872D01*
X441429Y-164831D01*
X442739Y-163664D01*
X444049Y-163373D01*
X445359Y-163664D01*
X446669Y-164831D01*
X447542Y-166872D01*
X447761Y-169206D01*
X447542Y-171539D01*
X446669Y-173581D01*
X445359Y-174747D01*
X444049Y-175039D01*
G01X457837Y-163373D02*
Y-171539D01*
X458711Y-173581D01*
X460021Y-174747D01*
X461549Y-175039D01*
X463077Y-174747D01*
X464387Y-173581D01*
X465261Y-171539D01*
G01Y-175039D02*
Y-163373D01*
G01X475992Y-175039D02*
Y-163373D01*
G01Y-165706D02*
X477084Y-164539D01*
X478176Y-163664D01*
X479704Y-163373D01*
X480795Y-163664D01*
X482106Y-164539D01*
G01X510992Y-175039D02*
Y-163373D01*
G01Y-165706D02*
X512084Y-164539D01*
X513176Y-163664D01*
X514704Y-163373D01*
X515795Y-163664D01*
X517106Y-164539D01*
G01X528274Y-167164D02*
X535261D01*
X534606Y-165122D01*
X533514Y-163956D01*
X531986Y-163373D01*
X530457Y-163664D01*
X529147Y-164539D01*
X528274Y-166581D01*
X527837Y-168331D01*
Y-170081D01*
X528274Y-171831D01*
X529366Y-173581D01*
X530676Y-174747D01*
X532204Y-175039D01*
X533732Y-174456D01*
X535261Y-172706D01*
G01X547739Y-175039D02*
Y-160164D01*
X548176Y-158706D01*
X549049Y-157831D01*
X550359Y-157539D01*
X551669Y-158122D01*
X552324Y-159581D01*
G01X549704Y-164539D02*
X545337D01*
G01X563274Y-167164D02*
X570261D01*
X569606Y-165122D01*
X568514Y-163956D01*
X566986Y-163373D01*
X565457Y-163664D01*
X564147Y-164539D01*
X563274Y-166581D01*
X562837Y-168331D01*
Y-170081D01*
X563274Y-171831D01*
X564366Y-173581D01*
X565676Y-174747D01*
X567204Y-175039D01*
X568732Y-174456D01*
X570261Y-172706D01*
G01X580992Y-175039D02*
Y-163373D01*
G01Y-165706D02*
X582084Y-164539D01*
X583176Y-163664D01*
X584704Y-163373D01*
X585795Y-163664D01*
X587106Y-164539D01*
G01X598274Y-167164D02*
X605261D01*
X604606Y-165122D01*
X603514Y-163956D01*
X601986Y-163373D01*
X600457Y-163664D01*
X599147Y-164539D01*
X598274Y-166581D01*
X597837Y-168331D01*
Y-170081D01*
X598274Y-171831D01*
X599366Y-173581D01*
X600676Y-174747D01*
X602204Y-175039D01*
X603732Y-174456D01*
X605261Y-172706D01*
G01X615337Y-175039D02*
Y-163373D01*
G01Y-166289D02*
X616211Y-164831D01*
X617521Y-163664D01*
X619267Y-163373D01*
X620795Y-163664D01*
X622106Y-164831D01*
X622761Y-166872D01*
Y-175039D01*
G01X640042Y-164831D02*
X638514Y-163664D01*
X637204Y-163373D01*
X635457Y-163956D01*
X634147Y-165122D01*
X633274Y-167164D01*
X633055Y-169206D01*
X633274Y-171248D01*
X634147Y-172998D01*
X635457Y-174456D01*
X637204Y-175039D01*
X638732Y-174456D01*
X640042Y-173289D01*
G01X650774Y-167164D02*
X657761D01*
X657106Y-165122D01*
X656014Y-163956D01*
X654486Y-163373D01*
X652957Y-163664D01*
X651647Y-164539D01*
X650774Y-166581D01*
X650337Y-168331D01*
Y-170081D01*
X650774Y-171831D01*
X651866Y-173581D01*
X653176Y-174747D01*
X654704Y-175039D01*
X656232Y-174456D01*
X657761Y-172706D01*
G01X689049Y-157539D02*
Y-175039D01*
G01X685992Y-163373D02*
X692106D01*
G01X706549Y-175039D02*
X705239Y-174747D01*
X703929Y-173581D01*
X703055Y-171539D01*
X702619Y-169206D01*
X703055Y-166872D01*
X703929Y-164831D01*
X705239Y-163664D01*
X706549Y-163373D01*
X707859Y-163664D01*
X709169Y-164831D01*
X710042Y-166872D01*
X710261Y-169206D01*
X710042Y-171539D01*
X709169Y-173581D01*
X707859Y-174747D01*
X706549Y-175039D01*
G01X740239D02*
Y-160164D01*
X740676Y-158706D01*
X741549Y-157831D01*
X742859Y-157539D01*
X744169Y-158122D01*
X744824Y-159581D01*
G01X742204Y-164539D02*
X737837D01*
G01X759049Y-163373D02*
Y-175039D01*
G01Y-158706D02*
X758612Y-158414D01*
Y-157831D01*
X759049Y-157539D01*
X759486Y-157831D01*
Y-158414D01*
X759049Y-158706D01*
G01X772837Y-175039D02*
Y-163373D01*
G01Y-166289D02*
X773711Y-164831D01*
X775021Y-163664D01*
X776767Y-163373D01*
X778295Y-163664D01*
X779606Y-164831D01*
X780261Y-166872D01*
Y-175039D01*
G01X797979Y-157539D02*
Y-175039D01*
G01Y-172415D02*
X797106Y-173873D01*
X795795Y-174747D01*
X794267Y-175039D01*
X792521Y-174456D01*
X791211Y-172998D01*
X790337Y-171248D01*
X790119Y-169206D01*
X790337Y-167164D01*
X791211Y-165414D01*
X792521Y-163956D01*
X794267Y-163373D01*
X795795Y-163664D01*
X796887Y-164248D01*
X797979Y-165414D01*
G01X829049Y-157539D02*
Y-175039D01*
G01X825992Y-163373D02*
X832106D01*
G01X842837Y-175039D02*
Y-157539D01*
G01Y-165997D02*
X843929Y-164539D01*
X845021Y-163664D01*
X846767Y-163373D01*
X848077Y-163664D01*
X849606Y-164831D01*
X850261Y-166581D01*
Y-175039D01*
G01X860774Y-167164D02*
X867761D01*
X867106Y-165122D01*
X866014Y-163956D01*
X864486Y-163373D01*
X862957Y-163664D01*
X861647Y-164539D01*
X860774Y-166581D01*
X860337Y-168331D01*
Y-170081D01*
X860774Y-171831D01*
X861866Y-173581D01*
X863176Y-174747D01*
X864704Y-175039D01*
X866232Y-174456D01*
X867761Y-172706D01*
G01X894246Y-175039D02*
Y-157539D01*
X898612D01*
X900359Y-158414D01*
X901669Y-159581D01*
X902761Y-161330D01*
X903634Y-163373D01*
X903852Y-166289D01*
X903634Y-169206D01*
X902761Y-171248D01*
X901669Y-172998D01*
X900359Y-174164D01*
X898612Y-175039D01*
X894246D01*
G01X912182D02*
Y-157539D01*
X917422D01*
X919169Y-158414D01*
X920479Y-160456D01*
X920916Y-162789D01*
X920479Y-165122D01*
X919387Y-166872D01*
X917422Y-167748D01*
X912182D01*
G01X951549Y-163373D02*
Y-175039D01*
G01Y-158706D02*
X951112Y-158414D01*
Y-157831D01*
X951549Y-157539D01*
X951986Y-157831D01*
Y-158414D01*
X951549Y-158706D01*
G01X962499Y-175039D02*
Y-163373D01*
G01Y-166581D02*
X963154Y-165122D01*
X964246Y-163956D01*
X965774Y-163373D01*
X967302Y-163956D01*
X968394Y-165122D01*
X969049Y-166581D01*
Y-175039D01*
G01Y-166581D02*
X969704Y-165122D01*
X970795Y-163956D01*
X972324Y-163373D01*
X973852Y-163956D01*
X974944Y-165122D01*
X975599Y-166872D01*
Y-175039D01*
G01X982619Y-180872D02*
Y-163373D01*
G01Y-165997D02*
X983711Y-164539D01*
X984802Y-163664D01*
X986549Y-163373D01*
X988077Y-163664D01*
X989606Y-165122D01*
X990261Y-167164D01*
X990479Y-169206D01*
X990261Y-171248D01*
X989606Y-173289D01*
X988295Y-174456D01*
X986549Y-175039D01*
X985021Y-174747D01*
X983492Y-173873D01*
X982619Y-172706D01*
G01X1000774Y-167164D02*
X1007761D01*
X1007106Y-165122D01*
X1006014Y-163956D01*
X1004486Y-163373D01*
X1002957Y-163664D01*
X1001647Y-164539D01*
X1000774Y-166581D01*
X1000337Y-168331D01*
Y-170081D01*
X1000774Y-171831D01*
X1001866Y-173581D01*
X1003176Y-174747D01*
X1004704Y-175039D01*
X1006232Y-174456D01*
X1007761Y-172706D01*
G01X1025479Y-157539D02*
Y-175039D01*
G01Y-172415D02*
X1024606Y-173873D01*
X1023295Y-174747D01*
X1021767Y-175039D01*
X1020021Y-174456D01*
X1018711Y-172998D01*
X1017837Y-171248D01*
X1017619Y-169206D01*
X1017837Y-167164D01*
X1018711Y-165414D01*
X1020021Y-163956D01*
X1021767Y-163373D01*
X1023295Y-163664D01*
X1024387Y-164248D01*
X1025479Y-165414D01*
G01X1042979Y-175039D02*
Y-163373D01*
G01Y-165414D02*
X1042106Y-164248D01*
X1040795Y-163664D01*
X1039267Y-163373D01*
X1037739Y-163956D01*
X1036429Y-165122D01*
X1035555Y-166872D01*
X1035119Y-169206D01*
X1035555Y-171539D01*
X1036429Y-173289D01*
X1037739Y-174456D01*
X1039267Y-175039D01*
X1040795Y-174747D01*
X1042106Y-173873D01*
X1042979Y-172706D01*
G01X1052837Y-175039D02*
Y-163373D01*
G01Y-166289D02*
X1053711Y-164831D01*
X1055021Y-163664D01*
X1056767Y-163373D01*
X1058295Y-163664D01*
X1059606Y-164831D01*
X1060261Y-166872D01*
Y-175039D01*
G01X1077542Y-164831D02*
X1076014Y-163664D01*
X1074704Y-163373D01*
X1072957Y-163956D01*
X1071647Y-165122D01*
X1070774Y-167164D01*
X1070555Y-169206D01*
X1070774Y-171248D01*
X1071647Y-172998D01*
X1072957Y-174456D01*
X1074704Y-175039D01*
X1076232Y-174456D01*
X1077542Y-173289D01*
G01X1088274Y-167164D02*
X1095261D01*
X1094606Y-165122D01*
X1093514Y-163956D01*
X1091986Y-163373D01*
X1090457Y-163664D01*
X1089147Y-164539D01*
X1088274Y-166581D01*
X1087837Y-168331D01*
Y-170081D01*
X1088274Y-171831D01*
X1089366Y-173581D01*
X1090676Y-174747D01*
X1092204Y-175039D01*
X1093732Y-174456D01*
X1095261Y-172706D01*
G01X1126549Y-157539D02*
Y-175039D01*
G01X1123492Y-163373D02*
X1129606D01*
G01X1140992Y-175039D02*
Y-163373D01*
G01Y-165706D02*
X1142084Y-164539D01*
X1143176Y-163664D01*
X1144704Y-163373D01*
X1145795Y-163664D01*
X1147106Y-164539D01*
G01X1165479Y-175039D02*
Y-163373D01*
G01Y-165414D02*
X1164606Y-164248D01*
X1163295Y-163664D01*
X1161767Y-163373D01*
X1160239Y-163956D01*
X1158929Y-165122D01*
X1158055Y-166872D01*
X1157619Y-169206D01*
X1158055Y-171539D01*
X1158929Y-173289D01*
X1160239Y-174456D01*
X1161767Y-175039D01*
X1163295Y-174747D01*
X1164606Y-173873D01*
X1165479Y-172706D01*
G01X1182542Y-164831D02*
X1181014Y-163664D01*
X1179704Y-163373D01*
X1177957Y-163956D01*
X1176647Y-165122D01*
X1175774Y-167164D01*
X1175555Y-169206D01*
X1175774Y-171248D01*
X1176647Y-172998D01*
X1177957Y-174456D01*
X1179704Y-175039D01*
X1181232Y-174456D01*
X1182542Y-173289D01*
G01X1193274Y-167164D02*
X1200261D01*
X1199606Y-165122D01*
X1198514Y-163956D01*
X1196986Y-163373D01*
X1195457Y-163664D01*
X1194147Y-164539D01*
X1193274Y-166581D01*
X1192837Y-168331D01*
Y-170081D01*
X1193274Y-171831D01*
X1194366Y-173581D01*
X1195676Y-174747D01*
X1197204Y-175039D01*
X1198732Y-174456D01*
X1200261Y-172706D01*
G01X1210774Y-172998D02*
X1211866Y-174164D01*
X1213394Y-175039D01*
X1214704D01*
X1216014Y-174456D01*
X1216887Y-173581D01*
X1217324Y-172415D01*
X1217106Y-170664D01*
X1216232Y-169789D01*
X1212302Y-168039D01*
X1211429Y-165997D01*
X1211866Y-164539D01*
X1212739Y-163664D01*
X1214049Y-163373D01*
X1215359Y-163664D01*
X1216669Y-164539D01*
G01X1249049Y-163373D02*
Y-175039D01*
G01Y-158706D02*
X1248612Y-158414D01*
Y-157831D01*
X1249049Y-157539D01*
X1249486Y-157831D01*
Y-158414D01*
X1249049Y-158706D01*
G01X1262837Y-175039D02*
Y-163373D01*
G01Y-166289D02*
X1263711Y-164831D01*
X1265021Y-163664D01*
X1266767Y-163373D01*
X1268295Y-163664D01*
X1269606Y-164831D01*
X1270261Y-166872D01*
Y-175039D01*
G01X1301549D02*
Y-157539D01*
G01X1322979Y-175039D02*
Y-163373D01*
G01Y-165414D02*
X1322106Y-164248D01*
X1320795Y-163664D01*
X1319267Y-163373D01*
X1317739Y-163956D01*
X1316429Y-165122D01*
X1315555Y-166872D01*
X1315119Y-169206D01*
X1315555Y-171539D01*
X1316429Y-173289D01*
X1317739Y-174456D01*
X1319267Y-175039D01*
X1320795Y-174747D01*
X1322106Y-173873D01*
X1322979Y-172706D01*
G01X1331964Y-180289D02*
X1333274Y-180872D01*
X1335021Y-180289D01*
X1336112Y-179123D01*
X1336986Y-177664D01*
X1338295Y-172998D01*
X1341134Y-163373D01*
G01X1334147D02*
X1338295Y-172998D01*
G01X1350774Y-167164D02*
X1357761D01*
X1357106Y-165122D01*
X1356014Y-163956D01*
X1354486Y-163373D01*
X1352957Y-163664D01*
X1351647Y-164539D01*
X1350774Y-166581D01*
X1350337Y-168331D01*
Y-170081D01*
X1350774Y-171831D01*
X1351866Y-173581D01*
X1353176Y-174747D01*
X1354704Y-175039D01*
X1356232Y-174456D01*
X1357761Y-172706D01*
G01X1368492Y-175039D02*
Y-163373D01*
G01Y-165706D02*
X1369584Y-164539D01*
X1370676Y-163664D01*
X1372204Y-163373D01*
X1373295Y-163664D01*
X1374606Y-164539D01*
G01X1402182Y-157539D02*
Y-175039D01*
X1410916D01*
G01X1419901Y-167748D02*
X1421429Y-165706D01*
X1422739Y-164539D01*
X1424486Y-163956D01*
X1426014Y-164539D01*
X1427106Y-165706D01*
X1427979Y-167456D01*
X1428197Y-169497D01*
X1427979Y-171248D01*
X1427106Y-172998D01*
X1425795Y-174456D01*
X1424267Y-175039D01*
X1422521Y-174456D01*
X1420992Y-172706D01*
X1420119Y-170081D01*
X1419901Y-167164D01*
X1420337Y-163373D01*
X1420992Y-161330D01*
X1422084Y-159289D01*
X1423612Y-157831D01*
X1425141Y-157539D01*
X1426669Y-158122D01*
X1427761Y-159581D01*
G01X1441549Y-175622D02*
X1441112Y-175331D01*
Y-174747D01*
X1441549Y-174456D01*
X1441986Y-174747D01*
Y-175331D01*
X1441549Y-175622D01*
G01X-1Y-113228D02*
Y-117165D01*
G03X7873Y-125039I7874J0D01*
G01X714566D01*
G03X722440Y-117165I0J7874D01*
G01Y-113228D01*
G01X1968Y40473D02*
X9842D01*
G02X11811Y38504I0J-1969D01*
G01Y-16772D01*
G02X9842Y-18740I-1969J1D01*
G01X1968D01*
G03X0Y-20709I0J-1968D01*
G01Y-97480D01*
G03X7874Y-105354I7874J0D01*
G01X341535D01*
G03X349409Y-97480I0J7874D01*
G01Y-15748D01*
G03X341535Y-7874I-7874J0D01*
G01X141338D01*
G02X133464Y0I0J7874D01*
G01Y250197D01*
G03X125590Y258071I-7874J0D01*
G01X1968D01*
G03X0Y256102I0J-1968D01*
G01Y236673D01*
G03X1968Y234705I1968J0D01*
G01X28346D01*
G02X30315Y232736I0J-1969D01*
G01Y216004D01*
G02X28346Y214036I-1968J0D01*
G01X23228D01*
G03X21259Y212067I0J-1969D01*
G01Y86752D01*
G03X23228Y84784I1969J1D01*
G01X28346D01*
G02X30315Y82815I0J-1969D01*
G01Y66083D01*
G02X28346Y64114I-1969J0D01*
G01X1968D01*
G03X0Y62146I0J-1968D01*
G01Y42441D01*
G03X1968Y40473I1968J0D01*
G01X-1Y-113228D02*
X13591D01*
G01X347441Y217598D02*
X339567D01*
G02X337598Y219567I0J1969D01*
G01Y274843D01*
G02X339567Y276811I1969J-1D01*
G01X347441D01*
G03X349409Y278780I0J1968D01*
G01Y355551D01*
G03X341535Y363425I-7874J0D01*
G01X7874D01*
G03X0Y355551I0J-7874D01*
G01Y273819D01*
G03X7874Y265945I7874J0D01*
G01X208071D01*
G02X215945Y258071I0J-7874D01*
G01Y7874D01*
G03X223819Y0I7874J0D01*
G01X347441D01*
G03X349409Y1969I0J1968D01*
G01Y21398D01*
G03X347441Y23366I-1968J0D01*
G01X321063D01*
G02X319094Y25335I0J1969D01*
G01Y42067D01*
G02X321063Y44035I1969J-1D01*
G01X326181D01*
G03X328150Y46004I0J1969D01*
G01Y171319D01*
G03X326181Y173287I-1968J0D01*
G01X321063D01*
G02X319094Y175256I0J1969D01*
G01Y191988D01*
G02X321063Y193957I1969J0D01*
G01X347441D01*
G03X349409Y195925I0J1968D01*
G01Y215630D01*
G03X347441Y217598I-1968J0D01*
G01X245745Y383110D02*
X7874D01*
G03X0Y375236I0J-7874D01*
G01Y371299D01*
G01D02*
X13591D01*
G01Y-113228D02*
G03Y-105354I0J3937D01*
G01Y258071D02*
G03Y265945I0J3937D01*
G01Y363425D02*
G03Y371299I0J3937D01*
G01X38787Y-113228D02*
X237000D01*
G01X38787Y-105354D02*
G03Y-113228I1J-3937D01*
G01Y265945D02*
G03Y258071I1J-3937D01*
G01X237000Y371299D02*
X38787D01*
G01D02*
G03Y363425I1J-3937D01*
G01X141338Y116437D02*
G03X133464I-3937J0D01*
G01Y141634D02*
G03X141338I3937J0D01*
G01Y0D02*
Y116437D01*
G01X162106Y0D02*
X141337D01*
G01X141338Y141634D02*
Y258071D01*
G01D02*
X162106D01*
G01Y-7874D02*
G03Y0I0J3937D01*
G01X179626Y62719D02*
G03X171044I-4291J0D01*
G03X179626I4291J0D01*
G01Y189063D02*
G03X171044Y189062I-4291J0D01*
G03X179626Y189063I4291J1D01*
G01X162106Y258071D02*
G03Y265945I0J3937D01*
G01X187302Y0D02*
G03Y-7874I1J-3937D01*
G01X208071Y0D02*
X187302D01*
G01Y265945D02*
G03Y258071I1J-3937D01*
G01D02*
X208071D01*
G01X207913Y0D02*
X208071D01*
G01Y116437D02*
Y0D01*
G01X215945Y116437D02*
G03X208071I-3937J0D01*
G01Y141634D02*
G03X215945I3937J0D01*
G01X208071Y258071D02*
Y141634D01*
G01X237000Y-113228D02*
G03Y-105354I0J3937D01*
G01Y363425D02*
G03Y371299I0J3937D01*
G01X245745Y383110D02*
G03X253619I3937J0D01*
G01X722440Y371299D02*
Y375236D01*
G03X714566Y383110I-7874J0D01*
G01X253619D01*
G01X262196Y-113228D02*
X460244D01*
G01X262196Y-105354D02*
G03Y-113228I0J-3937D01*
G01Y371299D02*
X460244D01*
G01X262196D02*
G03Y363425I0J-3937D01*
G01X310621Y-7874D02*
G03Y0I0J3937D01*
G01X335817D02*
G03Y-7874I1J-3937D01*
G01X353346Y-47481D02*
G03X349409Y-51418I0J-3937D01*
G01Y-20709D02*
G03X353346Y-24646I3937J0D01*
G01Y282717D02*
G03X349409Y278780I0J-3937D01*
G01Y309489D02*
G03X353346Y305552I3937J0D01*
G01Y-47481D02*
X369094D01*
G01X373031Y-51418D02*
G03X369094Y-47481I-3937J0D01*
G01X353346Y-24646D02*
X369094D01*
G01D02*
G03X373031Y-20709I0J3937D01*
G01X353346Y282717D02*
X369094D01*
G01X373031Y278780D02*
G03X369094Y282717I-3937J0D01*
G01X353346Y305552D02*
X369094D01*
G01D02*
G03X373031Y309489I0J3937D01*
G01X374999Y40473D02*
X382873D01*
G02X384842Y38504I0J-1969D01*
G01Y-16772D01*
G02X382873Y-18740I-1969J1D01*
G01X374999D01*
G03X373031Y-20709I0J-1968D01*
G01Y-97480D01*
G03X380905Y-105354I7874J0D01*
G01X714566D01*
G03X722440Y-97480I0J7874D01*
G01Y-15748D01*
G03X714566Y-7874I-7874J0D01*
G01X514369D01*
G02X506495Y0I0J7874D01*
G01Y250197D01*
G03X498621Y258071I-7874J0D01*
G01X374999D01*
G03X373031Y256102I0J-1968D01*
G01Y236673D01*
G03X374999Y234705I1968J0D01*
G01X401377D01*
G02X403346Y232736I0J-1969D01*
G01Y216004D01*
G02X401377Y214036I-1968J0D01*
G01X396259D01*
G03X394290Y212067I0J-1969D01*
G01Y86752D01*
G03X396259Y84784I1969J1D01*
G01X401377D01*
G02X403346Y82815I0J-1969D01*
G01Y66083D01*
G02X401377Y64114I-1969J0D01*
G01X374999D01*
G03X373031Y62146I0J-1968D01*
G01Y42441D01*
G03X374999Y40473I1968J0D01*
G01X720472Y217598D02*
X712598D01*
G02X710629Y219567I0J1969D01*
G01Y274843D01*
G02X712598Y276811I1969J-1D01*
G01X720472D01*
G03X722440Y278780I0J1968D01*
G01Y355551D01*
G03X714566Y363425I-7874J0D01*
G01X380905D01*
G03X373031Y355551I0J-7874D01*
G01Y273819D01*
G03X380905Y265945I7874J0D01*
G01X581102D01*
G02X588976Y258071I0J-7874D01*
G01Y7874D01*
G03X596850Y0I7874J0D01*
G01X720472D01*
G03X722440Y1969I0J1968D01*
G01Y21398D01*
G03X720472Y23366I-1968J0D01*
G01X694094D01*
G02X692125Y25335I0J1969D01*
G01Y42067D01*
G02X694094Y44035I1969J-1D01*
G01X699212D01*
G03X701181Y46004I0J1969D01*
G01Y171319D01*
G03X699212Y173287I-1969J-1D01*
G01X694094D01*
G02X692125Y175256I0J1969D01*
G01Y191988D01*
G02X694094Y193957I1969J0D01*
G01X720472D01*
G03X722440Y195925I0J1968D01*
G01Y215630D01*
G03X720472Y217598I-1968J0D01*
G01X386622Y258071D02*
G03Y265945I0J3937D01*
G01X411819D02*
G03Y258071I0J-3937D01*
G01X460244Y-113228D02*
G03Y-105354I0J3937D01*
G01Y363425D02*
G03Y371299I0J3937D01*
G01X485441Y-105354D02*
G03Y-113228I0J-3937D01*
G01Y371299D02*
G03Y363425I0J-3937D01*
G01Y-113228D02*
X683652D01*
G01X485441Y371299D02*
X683652D01*
G01X514369Y0D02*
Y116437D01*
G01X535137Y0D02*
X514369D01*
G01Y116437D02*
G03X506494I-3937J0D01*
G01Y141634D02*
G03X514369I3937J0D01*
G01D02*
Y258071D01*
G01D02*
X535137D01*
G01Y-7874D02*
G03Y0I0J3937D01*
G01X551396Y69008D02*
G03X542813I-4291J0D01*
G03X551396I4291J0D01*
G01Y195351D02*
G03X542813Y195352I-4292J0D01*
G03X551396Y195351I4291J-1D01*
G01X535137Y258071D02*
G03Y265945I0J3937D01*
G01X560333Y0D02*
G03Y-7874I1J-3937D01*
G01X581102Y0D02*
X560333D01*
G01Y265945D02*
G03Y258071I1J-3937D01*
G01D02*
X581102D01*
G01Y116437D02*
Y0D01*
G01X588976Y116437D02*
G03X581102I-3937J0D01*
G01Y141634D02*
G03X588976I3937J0D01*
G01X581102Y258071D02*
Y141634D01*
G01X683652Y-113228D02*
G03Y-105354I0J3937D01*
G01Y-7874D02*
G03Y0I0J3937D01*
G01Y363425D02*
G03Y371299I0J3937D01*
G01X708848Y-113228D02*
X722440D01*
G01X708848Y-105354D02*
G03Y-113228I1J-3937D01*
G01Y0D02*
G03Y-7874I1J-3937D01*
G01Y371299D02*
X722440D01*
G01X708848D02*
G03Y363425I1J-3937D01*
G01X774187Y358210D02*
Y375710D01*
X778553D01*
X780300Y374835D01*
X781610Y373668D01*
X782702Y371919D01*
X783575Y369876D01*
X783793Y366960D01*
X783575Y364043D01*
X782702Y362001D01*
X781610Y360251D01*
X780300Y359085D01*
X778553Y358210D01*
X774187D01*
G01X792123D02*
Y375710D01*
X797363D01*
X799110Y374835D01*
X800420Y372793D01*
X800857Y370460D01*
X800420Y368127D01*
X799328Y366377D01*
X797363Y365501D01*
X792123D01*
G01X828870Y375710D02*
X834110D01*
G01X831490D02*
Y358210D01*
G01X828870D02*
X834110D01*
G01X843313D02*
Y375710D01*
X848990Y361127D01*
X854667Y375710D01*
Y358210D01*
G01X862123D02*
Y375710D01*
X867363D01*
X869110Y374835D01*
X870420Y372793D01*
X870857Y370460D01*
X870420Y368127D01*
X869328Y366377D01*
X867363Y365501D01*
X862123D01*
G01X888357Y358210D02*
X879623D01*
Y375710D01*
X888357D01*
G01X884863Y367252D02*
X879623D01*
G01X896687Y358210D02*
Y375710D01*
X901053D01*
X902800Y374835D01*
X904110Y373668D01*
X905202Y371919D01*
X906075Y369876D01*
X906293Y366960D01*
X906075Y364043D01*
X905202Y362001D01*
X904110Y360251D01*
X902800Y359085D01*
X901053Y358210D01*
X896687D01*
G01X913531D02*
X918990Y375710D01*
X924449Y358210D01*
G01X922483Y364335D02*
X915496D01*
G01X931468Y358210D02*
Y375710D01*
X941512Y358210D01*
Y375710D01*
G01X958793Y374251D02*
X957483Y375127D01*
X955955Y375710D01*
X954208D01*
X952243Y374835D01*
X950715Y373377D01*
X949623Y371626D01*
X948750Y368710D01*
X948531Y366085D01*
X948968Y363460D01*
X949623Y361710D01*
X950933Y359960D01*
X952462Y358793D01*
X953990Y358210D01*
X955518D01*
X957047Y358793D01*
X958357Y359668D01*
X959449Y360834D01*
G01X975857Y358210D02*
X967123D01*
Y375710D01*
X975857D01*
G01X972363Y367252D02*
X967123D01*
G01X1006490Y375710D02*
Y358210D01*
G01X1001468Y375710D02*
X1011512D01*
G01X1018531Y358210D02*
X1023990Y375710D01*
X1029449Y358210D01*
G01X1027483Y364335D02*
X1020496D01*
G01X1043236Y367543D02*
X1044110Y368418D01*
X1044765Y369876D01*
X1045202Y371919D01*
X1044765Y373668D01*
X1043892Y374835D01*
X1042363Y375710D01*
X1036468D01*
Y358210D01*
X1043673D01*
X1045202Y359376D01*
X1046075Y361127D01*
X1046512Y363168D01*
X1046075Y365210D01*
X1044765Y366960D01*
X1043236Y367543D01*
X1036468D01*
G01X1054623Y375710D02*
Y358210D01*
X1063357D01*
G01X1080857D02*
X1072123D01*
Y375710D01*
X1080857D01*
G01X1077363Y367252D02*
X1072123D01*
G01X1093990Y357627D02*
X1093553Y357918D01*
Y358502D01*
X1093990Y358793D01*
X1094427Y358502D01*
Y357918D01*
X1093990Y357627D01*
G01Y365501D02*
X1093553Y365793D01*
Y366377D01*
X1093990Y366668D01*
X1094427Y366377D01*
Y365793D01*
X1093990Y365501D01*
G01X1124623Y375710D02*
Y358210D01*
X1133357D01*
G01X1142342Y365501D02*
X1143870Y367543D01*
X1145180Y368710D01*
X1146927Y369293D01*
X1148455Y368710D01*
X1149547Y367543D01*
X1150420Y365793D01*
X1150638Y363752D01*
X1150420Y362001D01*
X1149547Y360251D01*
X1148236Y358793D01*
X1146708Y358210D01*
X1144962Y358793D01*
X1143433Y360543D01*
X1142560Y363168D01*
X1142342Y366085D01*
X1142778Y369876D01*
X1143433Y371919D01*
X1144525Y373960D01*
X1146053Y375418D01*
X1147582Y375710D01*
X1149110Y375127D01*
X1150202Y373668D01*
G01X796070Y341060D02*
X801310D01*
G01X798690D02*
Y323560D01*
G01X796070D02*
X801310D01*
G01X810513D02*
Y341060D01*
X816190Y326477D01*
X821867Y341060D01*
Y323560D01*
G01X829323D02*
Y341060D01*
X834563D01*
X836310Y340185D01*
X837620Y338143D01*
X838057Y335810D01*
X837620Y333477D01*
X836528Y331727D01*
X834563Y330851D01*
X829323D01*
G01X850098Y317727D02*
X847915Y320643D01*
X846823Y323560D01*
Y335226D01*
X847915Y338143D01*
X850098Y341060D01*
G01X868690Y323560D02*
X866943Y323852D01*
X865415Y325018D01*
X864105Y326768D01*
X863231Y328810D01*
X862795Y331143D01*
Y333477D01*
X863231Y335810D01*
X864105Y337852D01*
X865415Y339601D01*
X866943Y340768D01*
X868690Y341060D01*
X870436Y340768D01*
X871965Y339601D01*
X873275Y337852D01*
X874149Y335810D01*
X874585Y333477D01*
Y331143D01*
X874149Y328810D01*
X873275Y326768D01*
X871965Y325018D01*
X870436Y323852D01*
X868690Y323560D01*
G01X882478D02*
Y341060D01*
G01Y332602D02*
X883570Y334060D01*
X884662Y334935D01*
X886408Y335226D01*
X887718Y334935D01*
X889247Y333768D01*
X889902Y332018D01*
Y323560D01*
G01X897140D02*
Y335226D01*
G01Y332018D02*
X897795Y333477D01*
X898887Y334643D01*
X900415Y335226D01*
X901943Y334643D01*
X903035Y333477D01*
X903690Y332018D01*
Y323560D01*
G01Y332018D02*
X904345Y333477D01*
X905436Y334643D01*
X906965Y335226D01*
X908493Y334643D01*
X909585Y333477D01*
X910240Y331727D01*
Y323560D01*
G01X922282Y317727D02*
X924465Y320643D01*
X925557Y323560D01*
Y335226D01*
X924465Y338143D01*
X922282Y341060D01*
G01X833690Y288910D02*
X835218Y289202D01*
X836965Y290076D01*
X838057Y291534D01*
X838493Y293577D01*
X838057Y295618D01*
X836747Y297368D01*
X834782Y298243D01*
X832598D01*
X831288Y298827D01*
X830196Y300285D01*
X829760Y302326D01*
X830415Y304368D01*
X831943Y305827D01*
X833690Y306410D01*
X835436Y305827D01*
X836965Y304368D01*
X837620Y302326D01*
X837183Y300285D01*
X836092Y298827D01*
X834782Y298243D01*
X832598D01*
X830633Y297368D01*
X829323Y295618D01*
X828887Y293577D01*
X829323Y291534D01*
X830415Y290076D01*
X832162Y289202D01*
X833690Y288910D01*
G01X846387Y291534D02*
X847696Y290076D01*
X849225Y289202D01*
X851190Y288910D01*
X853155Y289493D01*
X854683Y290660D01*
X855775Y292701D01*
X855993Y295035D01*
X855557Y297368D01*
X854465Y298827D01*
X852936Y299993D01*
X851408Y300285D01*
X849880Y299993D01*
X847915Y298827D01*
X848570Y306410D01*
X854465D01*
G01X868690Y288327D02*
X868253Y288618D01*
Y289202D01*
X868690Y289493D01*
X869127Y289202D01*
Y288618D01*
X868690Y288327D01*
G01X886190Y306410D02*
X884443Y305827D01*
X883133Y304368D01*
X882260Y302619D01*
X881605Y300285D01*
X881387Y297660D01*
X881605Y295035D01*
X882260Y292701D01*
X883133Y290951D01*
X884443Y289493D01*
X886190Y288910D01*
X887936Y289493D01*
X889247Y290951D01*
X890120Y292701D01*
X890775Y295035D01*
X890993Y297660D01*
X890775Y300285D01*
X890120Y302619D01*
X889247Y304368D01*
X887936Y305827D01*
X886190Y306410D01*
G01X1010890Y341060D02*
X1013946Y323560D01*
X1017440Y341060D01*
X1020933Y323560D01*
X1023990Y341060D01*
G01X1032320D02*
X1037560D01*
G01X1034940D02*
Y323560D01*
G01X1032320D02*
X1037560D01*
G01X1047637D02*
Y341060D01*
X1052003D01*
X1053750Y340185D01*
X1055060Y339018D01*
X1056152Y337269D01*
X1057025Y335226D01*
X1057243Y332310D01*
X1057025Y329393D01*
X1056152Y327351D01*
X1055060Y325601D01*
X1053750Y324435D01*
X1052003Y323560D01*
X1047637D01*
G01X1069940Y341060D02*
Y323560D01*
G01X1064918Y341060D02*
X1074962D01*
G01X1082855Y323560D02*
Y341060D01*
G01X1092025D02*
Y323560D01*
G01Y332310D02*
X1082855D01*
G01X1103848Y317727D02*
X1101665Y320643D01*
X1100573Y323560D01*
Y335226D01*
X1101665Y338143D01*
X1103848Y341060D01*
G01X1115890Y323560D02*
Y335226D01*
G01Y332018D02*
X1116545Y333477D01*
X1117637Y334643D01*
X1119165Y335226D01*
X1120693Y334643D01*
X1121785Y333477D01*
X1122440Y332018D01*
Y323560D01*
G01Y332018D02*
X1123095Y333477D01*
X1124186Y334643D01*
X1125715Y335226D01*
X1127243Y334643D01*
X1128335Y333477D01*
X1128990Y331727D01*
Y323560D01*
G01X1139940Y335226D02*
Y323560D01*
G01Y339893D02*
X1139503Y340185D01*
Y340768D01*
X1139940Y341060D01*
X1140377Y340768D01*
Y340185D01*
X1139940Y339893D01*
G01X1157440Y323560D02*
Y341060D01*
G01X1171665Y325601D02*
X1172757Y324435D01*
X1174285Y323560D01*
X1175595D01*
X1176905Y324143D01*
X1177778Y325018D01*
X1178215Y326184D01*
X1177997Y327935D01*
X1177123Y328810D01*
X1173193Y330560D01*
X1172320Y332602D01*
X1172757Y334060D01*
X1173630Y334935D01*
X1174940Y335226D01*
X1176250Y334935D01*
X1177560Y334060D01*
G01X1193532Y317727D02*
X1195715Y320643D01*
X1196807Y323560D01*
Y335226D01*
X1195715Y338143D01*
X1193532Y341060D01*
G01X1038887Y291534D02*
X1040196Y290076D01*
X1041725Y289202D01*
X1043690Y288910D01*
X1045655Y289493D01*
X1047183Y290660D01*
X1048275Y292701D01*
X1048493Y295035D01*
X1048057Y297368D01*
X1046965Y298827D01*
X1045436Y299993D01*
X1043908Y300285D01*
X1042380Y299993D01*
X1040415Y298827D01*
X1041070Y306410D01*
X1046965D01*
G01X1061190Y288327D02*
X1060753Y288618D01*
Y289202D01*
X1061190Y289493D01*
X1061627Y289202D01*
Y288618D01*
X1061190Y288327D01*
G01X1074542Y303493D02*
X1075852Y305243D01*
X1077380Y306118D01*
X1079127Y306410D01*
X1081310Y305827D01*
X1082838Y304368D01*
X1083275Y302619D01*
X1083057Y300868D01*
X1082183Y299410D01*
X1077817Y296493D01*
X1075852Y294452D01*
X1074542Y291534D01*
X1074105Y288910D01*
X1083275D01*
G01X1091387Y291534D02*
X1092696Y290076D01*
X1094225Y289202D01*
X1096190Y288910D01*
X1098155Y289493D01*
X1099683Y290660D01*
X1100775Y292701D01*
X1100993Y295035D01*
X1100557Y297368D01*
X1099465Y298827D01*
X1097936Y299993D01*
X1096408Y300285D01*
X1094880Y299993D01*
X1092915Y298827D01*
X1093570Y306410D01*
X1099465D01*
G01X1109760Y288327D02*
X1117620Y306410D01*
G01X1130753Y288910D02*
X1131190Y292701D01*
X1131845Y295910D01*
X1132718Y298827D01*
X1133810Y302035D01*
X1135557Y306410D01*
X1126823D01*
G01X1148690Y288327D02*
X1148253Y288618D01*
Y289202D01*
X1148690Y289493D01*
X1149127Y289202D01*
Y288618D01*
X1148690Y288327D01*
G01X1161387Y291534D02*
X1162696Y290076D01*
X1164225Y289202D01*
X1166190Y288910D01*
X1168155Y289493D01*
X1169683Y290660D01*
X1170775Y292701D01*
X1170993Y295035D01*
X1170557Y297368D01*
X1169465Y298827D01*
X1167936Y299993D01*
X1166408Y300285D01*
X1164880Y299993D01*
X1162915Y298827D01*
X1163570Y306410D01*
X1169465D01*
G01X1288690Y341060D02*
Y323560D01*
G01X1283668Y341060D02*
X1293712D01*
G01X1306190Y323560D02*
Y331435D01*
X1301823Y341060D01*
G01X1310557D02*
X1306190Y331435D01*
G01X1319323Y323560D02*
Y341060D01*
X1324563D01*
X1326310Y340185D01*
X1327620Y338143D01*
X1328057Y335810D01*
X1327620Y333477D01*
X1326528Y331727D01*
X1324563Y330851D01*
X1319323D01*
G01X1345557Y323560D02*
X1336823D01*
Y341060D01*
X1345557D01*
G01X1342063Y332602D02*
X1336823D01*
G01X1301387Y288910D02*
Y306410D01*
X1305753D01*
X1307500Y305535D01*
X1308810Y304368D01*
X1309902Y302619D01*
X1310775Y300576D01*
X1310993Y297660D01*
X1310775Y294743D01*
X1309902Y292701D01*
X1308810Y290951D01*
X1307500Y289785D01*
X1305753Y288910D01*
X1301387D01*
G01X1319323D02*
Y306410D01*
X1324563D01*
X1326310Y305535D01*
X1327620Y303493D01*
X1328057Y301160D01*
X1327620Y298827D01*
X1326528Y297077D01*
X1324563Y296201D01*
X1319323D01*
G01X1389323Y323560D02*
Y341060D01*
X1394782D01*
X1396528Y340185D01*
X1397620Y339018D01*
X1398057Y336685D01*
X1397620Y334351D01*
X1396310Y332893D01*
X1394782Y332018D01*
X1389323D01*
G01X1394782D02*
X1398057Y323560D01*
G01X1407915Y331435D02*
X1414902D01*
X1414247Y333477D01*
X1413155Y334643D01*
X1411627Y335226D01*
X1410098Y334935D01*
X1408788Y334060D01*
X1407915Y332018D01*
X1407478Y330268D01*
Y328518D01*
X1407915Y326768D01*
X1409007Y325018D01*
X1410317Y323852D01*
X1411845Y323560D01*
X1413373Y324143D01*
X1414902Y325893D01*
G01X1427380Y323560D02*
Y338435D01*
X1427817Y339893D01*
X1428690Y340768D01*
X1430000Y341060D01*
X1431310Y340477D01*
X1431965Y339018D01*
G01X1429345Y334060D02*
X1424978D01*
G01X1446190Y322977D02*
X1445753Y323268D01*
Y323852D01*
X1446190Y324143D01*
X1446627Y323852D01*
Y323268D01*
X1446190Y322977D01*
G01X1476823Y323560D02*
Y341060D01*
X1482063D01*
X1483810Y340185D01*
X1485120Y338143D01*
X1485557Y335810D01*
X1485120Y333477D01*
X1484028Y331727D01*
X1482063Y330851D01*
X1476823D01*
G01X1498690Y323560D02*
Y341060D01*
G01X1520120Y323560D02*
Y335226D01*
G01Y333185D02*
X1519247Y334351D01*
X1517936Y334935D01*
X1516408Y335226D01*
X1514880Y334643D01*
X1513570Y333477D01*
X1512696Y331727D01*
X1512260Y329393D01*
X1512696Y327060D01*
X1513570Y325310D01*
X1514880Y324143D01*
X1516408Y323560D01*
X1517936Y323852D01*
X1519247Y324726D01*
X1520120Y325893D01*
G01X1529978Y323560D02*
Y335226D01*
G01Y332310D02*
X1530852Y333768D01*
X1532162Y334935D01*
X1533908Y335226D01*
X1535436Y334935D01*
X1536747Y333768D01*
X1537402Y331727D01*
Y323560D01*
G01X1547915Y331435D02*
X1554902D01*
X1554247Y333477D01*
X1553155Y334643D01*
X1551627Y335226D01*
X1550098Y334935D01*
X1548788Y334060D01*
X1547915Y332018D01*
X1547478Y330268D01*
Y328518D01*
X1547915Y326768D01*
X1549007Y325018D01*
X1550317Y323852D01*
X1551845Y323560D01*
X1553373Y324143D01*
X1554902Y325893D01*
G01X1433073Y306410D02*
Y288910D01*
X1441807D01*
G01X1450137Y291534D02*
X1451446Y290076D01*
X1452975Y289202D01*
X1454940Y288910D01*
X1456905Y289493D01*
X1458433Y290660D01*
X1459525Y292701D01*
X1459743Y295035D01*
X1459307Y297368D01*
X1458215Y298827D01*
X1456686Y299993D01*
X1455158Y300285D01*
X1453630Y299993D01*
X1451665Y298827D01*
X1452320Y306410D01*
X1458215D01*
G01X1468510Y288327D02*
X1476370Y306410D01*
G01X1485573D02*
Y288910D01*
X1494307D01*
G01X1507003D02*
X1507440Y292701D01*
X1508095Y295910D01*
X1508968Y298827D01*
X1510060Y302035D01*
X1511807Y306410D01*
X1503073D01*
G01X1668990Y300576D02*
Y288910D01*
G01Y305243D02*
X1668553Y305535D01*
Y306118D01*
X1668990Y306410D01*
X1669427Y306118D01*
Y305535D01*
X1668990Y305243D01*
G01X1683215Y290951D02*
X1684307Y289785D01*
X1685835Y288910D01*
X1687145D01*
X1688455Y289493D01*
X1689328Y290368D01*
X1689765Y291534D01*
X1689547Y293285D01*
X1688673Y294160D01*
X1684743Y295910D01*
X1683870Y297952D01*
X1684307Y299410D01*
X1685180Y300285D01*
X1686490Y300576D01*
X1687800Y300285D01*
X1689110Y299410D01*
G01X1716468Y288910D02*
Y306410D01*
X1726512Y288910D01*
Y306410D01*
G01X1738990Y288910D02*
X1737243Y289202D01*
X1735715Y290368D01*
X1734405Y292118D01*
X1733531Y294160D01*
X1733095Y296493D01*
Y298827D01*
X1733531Y301160D01*
X1734405Y303202D01*
X1735715Y304951D01*
X1737243Y306118D01*
X1738990Y306410D01*
X1740736Y306118D01*
X1742265Y304951D01*
X1743575Y303202D01*
X1744449Y301160D01*
X1744885Y298827D01*
Y296493D01*
X1744449Y294160D01*
X1743575Y292118D01*
X1742265Y290368D01*
X1740736Y289202D01*
X1738990Y288910D01*
G01X1756490Y306410D02*
Y288910D01*
G01X1751468Y306410D02*
X1761512D01*
G01X1787778Y300576D02*
Y292410D01*
X1788652Y290368D01*
X1789962Y289202D01*
X1791490Y288910D01*
X1793018Y289202D01*
X1794328Y290368D01*
X1795202Y292410D01*
G01Y288910D02*
Y300576D01*
G01X1805715Y290951D02*
X1806807Y289785D01*
X1808335Y288910D01*
X1809645D01*
X1810955Y289493D01*
X1811828Y290368D01*
X1812265Y291534D01*
X1812047Y293285D01*
X1811173Y294160D01*
X1807243Y295910D01*
X1806370Y297952D01*
X1806807Y299410D01*
X1807680Y300285D01*
X1808990Y300576D01*
X1810300Y300285D01*
X1811610Y299410D01*
G01X1823215Y296785D02*
X1830202D01*
X1829547Y298827D01*
X1828455Y299993D01*
X1826927Y300576D01*
X1825398Y300285D01*
X1824088Y299410D01*
X1823215Y297368D01*
X1822778Y295618D01*
Y293868D01*
X1823215Y292118D01*
X1824307Y290368D01*
X1825617Y289202D01*
X1827145Y288910D01*
X1828673Y289493D01*
X1830202Y291243D01*
G01X1847920Y306410D02*
Y288910D01*
G01Y291534D02*
X1847047Y290076D01*
X1845736Y289202D01*
X1844208Y288910D01*
X1842462Y289493D01*
X1841152Y290951D01*
X1840278Y292701D01*
X1840060Y294743D01*
X1840278Y296785D01*
X1841152Y298535D01*
X1842462Y299993D01*
X1844208Y300576D01*
X1845736Y300285D01*
X1846828Y299701D01*
X1847920Y298535D01*
G01X1594187Y322977D02*
X1603793Y335810D01*
G01X1598990Y338143D02*
Y320643D01*
G01X1603793Y322977D02*
X1594187Y335810D01*
G01X1592440Y329393D02*
X1605540D01*
G01X1631152D02*
X1636828D01*
G01X1664187Y323560D02*
Y341060D01*
X1668553D01*
X1670300Y340185D01*
X1671610Y339018D01*
X1672702Y337269D01*
X1673575Y335226D01*
X1673793Y332310D01*
X1673575Y329393D01*
X1672702Y327351D01*
X1671610Y325601D01*
X1670300Y324435D01*
X1668553Y323560D01*
X1664187D01*
G01X1683215Y331435D02*
X1690202D01*
X1689547Y333477D01*
X1688455Y334643D01*
X1686927Y335226D01*
X1685398Y334935D01*
X1684088Y334060D01*
X1683215Y332018D01*
X1682778Y330268D01*
Y328518D01*
X1683215Y326768D01*
X1684307Y325018D01*
X1685617Y323852D01*
X1687145Y323560D01*
X1688673Y324143D01*
X1690202Y325893D01*
G01X1700278Y323560D02*
Y335226D01*
G01Y332310D02*
X1701152Y333768D01*
X1702462Y334935D01*
X1704208Y335226D01*
X1705736Y334935D01*
X1707047Y333768D01*
X1707702Y331727D01*
Y323560D01*
G01X1721490D02*
X1720180Y323852D01*
X1718870Y325018D01*
X1717996Y327060D01*
X1717560Y329393D01*
X1717996Y331727D01*
X1718870Y333768D01*
X1720180Y334935D01*
X1721490Y335226D01*
X1722800Y334935D01*
X1724110Y333768D01*
X1724983Y331727D01*
X1725202Y329393D01*
X1724983Y327060D01*
X1724110Y325018D01*
X1722800Y323852D01*
X1721490Y323560D01*
G01X1738990Y341060D02*
Y323560D01*
G01X1735933Y335226D02*
X1742047D01*
G01X1753215Y331435D02*
X1760202D01*
X1759547Y333477D01*
X1758455Y334643D01*
X1756927Y335226D01*
X1755398Y334935D01*
X1754088Y334060D01*
X1753215Y332018D01*
X1752778Y330268D01*
Y328518D01*
X1753215Y326768D01*
X1754307Y325018D01*
X1755617Y323852D01*
X1757145Y323560D01*
X1758673Y324143D01*
X1760202Y325893D01*
G01X1770715Y325601D02*
X1771807Y324435D01*
X1773335Y323560D01*
X1774645D01*
X1775955Y324143D01*
X1776828Y325018D01*
X1777265Y326184D01*
X1777047Y327935D01*
X1776173Y328810D01*
X1772243Y330560D01*
X1771370Y332602D01*
X1771807Y334060D01*
X1772680Y334935D01*
X1773990Y335226D01*
X1775300Y334935D01*
X1776610Y334060D01*
G01X1808990Y341060D02*
Y323560D01*
G01X1805933Y335226D02*
X1812047D01*
G01X1822778Y323560D02*
Y341060D01*
G01Y332602D02*
X1823870Y334060D01*
X1824962Y334935D01*
X1826708Y335226D01*
X1828018Y334935D01*
X1829547Y333768D01*
X1830202Y332018D01*
Y323560D01*
G01X1847920D02*
Y335226D01*
G01Y333185D02*
X1847047Y334351D01*
X1845736Y334935D01*
X1844208Y335226D01*
X1842680Y334643D01*
X1841370Y333477D01*
X1840496Y331727D01*
X1840060Y329393D01*
X1840496Y327060D01*
X1841370Y325310D01*
X1842680Y324143D01*
X1844208Y323560D01*
X1845736Y323852D01*
X1847047Y324726D01*
X1847920Y325893D01*
G01X1861490Y341060D02*
Y323560D01*
G01X1858433Y335226D02*
X1864547D01*
G01X1896490Y341060D02*
Y323560D01*
G01X1893433Y335226D02*
X1899547D01*
G01X1910278Y323560D02*
Y341060D01*
G01Y332602D02*
X1911370Y334060D01*
X1912462Y334935D01*
X1914208Y335226D01*
X1915518Y334935D01*
X1917047Y333768D01*
X1917702Y332018D01*
Y323560D01*
G01X1931490Y335226D02*
Y323560D01*
G01Y339893D02*
X1931053Y340185D01*
Y340768D01*
X1931490Y341060D01*
X1931927Y340768D01*
Y340185D01*
X1931490Y339893D01*
G01X1945715Y325601D02*
X1946807Y324435D01*
X1948335Y323560D01*
X1949645D01*
X1950955Y324143D01*
X1951828Y325018D01*
X1952265Y326184D01*
X1952047Y327935D01*
X1951173Y328810D01*
X1947243Y330560D01*
X1946370Y332602D01*
X1946807Y334060D01*
X1947680Y334935D01*
X1948990Y335226D01*
X1950300Y334935D01*
X1951610Y334060D01*
G01X1981370Y341060D02*
X1986610D01*
G01X1983990D02*
Y323560D01*
G01X1981370D02*
X1986610D01*
G01X1994940D02*
Y335226D01*
G01Y332018D02*
X1995595Y333477D01*
X1996687Y334643D01*
X1998215Y335226D01*
X1999743Y334643D01*
X2000835Y333477D01*
X2001490Y332018D01*
Y323560D01*
G01Y332018D02*
X2002145Y333477D01*
X2003236Y334643D01*
X2004765Y335226D01*
X2006293Y334643D01*
X2007385Y333477D01*
X2008040Y331727D01*
Y323560D01*
G01X2015060Y317727D02*
Y335226D01*
G01Y332602D02*
X2016152Y334060D01*
X2017243Y334935D01*
X2018990Y335226D01*
X2020518Y334935D01*
X2022047Y333477D01*
X2022702Y331435D01*
X2022920Y329393D01*
X2022702Y327351D01*
X2022047Y325310D01*
X2020736Y324143D01*
X2018990Y323560D01*
X2017462Y323852D01*
X2015933Y324726D01*
X2015060Y325893D01*
G01X2033215Y331435D02*
X2040202D01*
X2039547Y333477D01*
X2038455Y334643D01*
X2036927Y335226D01*
X2035398Y334935D01*
X2034088Y334060D01*
X2033215Y332018D01*
X2032778Y330268D01*
Y328518D01*
X2033215Y326768D01*
X2034307Y325018D01*
X2035617Y323852D01*
X2037145Y323560D01*
X2038673Y324143D01*
X2040202Y325893D01*
G01X2057920Y341060D02*
Y323560D01*
G01Y326184D02*
X2057047Y324726D01*
X2055736Y323852D01*
X2054208Y323560D01*
X2052462Y324143D01*
X2051152Y325601D01*
X2050278Y327351D01*
X2050060Y329393D01*
X2050278Y331435D01*
X2051152Y333185D01*
X2052462Y334643D01*
X2054208Y335226D01*
X2055736Y334935D01*
X2056828Y334351D01*
X2057920Y333185D01*
G01X2075420Y323560D02*
Y335226D01*
G01Y333185D02*
X2074547Y334351D01*
X2073236Y334935D01*
X2071708Y335226D01*
X2070180Y334643D01*
X2068870Y333477D01*
X2067996Y331727D01*
X2067560Y329393D01*
X2067996Y327060D01*
X2068870Y325310D01*
X2070180Y324143D01*
X2071708Y323560D01*
X2073236Y323852D01*
X2074547Y324726D01*
X2075420Y325893D01*
G01X2085278Y323560D02*
Y335226D01*
G01Y332310D02*
X2086152Y333768D01*
X2087462Y334935D01*
X2089208Y335226D01*
X2090736Y334935D01*
X2092047Y333768D01*
X2092702Y331727D01*
Y323560D01*
G01X2109983Y333768D02*
X2108455Y334935D01*
X2107145Y335226D01*
X2105398Y334643D01*
X2104088Y333477D01*
X2103215Y331435D01*
X2102996Y329393D01*
X2103215Y327351D01*
X2104088Y325601D01*
X2105398Y324143D01*
X2107145Y323560D01*
X2108673Y324143D01*
X2109983Y325310D01*
G01X2120715Y331435D02*
X2127702D01*
X2127047Y333477D01*
X2125955Y334643D01*
X2124427Y335226D01*
X2122898Y334935D01*
X2121588Y334060D01*
X2120715Y332018D01*
X2120278Y330268D01*
Y328518D01*
X2120715Y326768D01*
X2121807Y325018D01*
X2123117Y323852D01*
X2124645Y323560D01*
X2126173Y324143D01*
X2127702Y325893D01*
G54D12*
G01X285715Y180981D02*
X291906Y174790D01*
G01X286617Y181883D02*
X287152Y181348D01*
G01X285715Y180981D02*
X291906Y174790D01*
G01X286000Y183372D02*
G03X286617Y181883I2105J0D01*
G01X284725Y183372D02*
G03X285715Y180981I3381J-1D01*
G01X286000Y184244D02*
Y183372D01*
G01X284725Y194889D02*
Y183372D01*
G01X286000Y190354D02*
Y188779D01*
G01X284725Y194889D02*
Y183372D01*
G01X286432Y195932D02*
G03X286000Y194889I1043J-1043D01*
G01X285530Y196834D02*
G03X284725Y194889I1945J-1944D01*
G01X285715Y180981D02*
X291906Y174790D01*
G01X286617Y181883D02*
X287152Y181348D01*
G01X284725Y183372D02*
G03X285715Y180981I3381J-1D01*
G01X286000Y183372D02*
G03X286617Y181883I2105J0D01*
G01X284725Y194889D02*
Y183372D01*
G01X286000Y184244D02*
Y183372D01*
G01Y190354D02*
Y188779D01*
G01X285530Y196834D02*
G03X284725Y194889I1945J-1944D01*
G01X286432Y195932D02*
G03X286000Y194889I1043J-1043D01*
G01X288200Y196281D02*
X287275D01*
G01X287500Y197556D02*
X287184D01*
G01X287500D02*
X287184D01*
G01X288200Y196281D02*
X287275D01*
G01X298275Y88937D02*
X296931D01*
G01X298274Y87662D02*
X296983D01*
G01X299056Y88787D02*
G03X298275Y88937I-782J-1961D01*
G01X298584Y87602D02*
G03X298274Y87662I-311J-776D01*
G01X299948Y88432D02*
X299056Y88787D01*
G01X299476Y87247D02*
X298584Y87602D01*
G01X300742Y88279D02*
G02X299948Y88432I1J2144D01*
G01X300741Y87004D02*
G02X299476Y87247I1J3419D01*
G01X312638Y87004D02*
X300741D01*
G01X298274Y87662D02*
X296983D01*
G01X298275Y88937D02*
X296931D01*
G01X298584Y87602D02*
G03X298274Y87662I-311J-776D01*
G01X299056Y88787D02*
G03X298275Y88937I-782J-1961D01*
G01X299476Y87247D02*
X298584Y87602D01*
G01X299948Y88432D02*
X299056Y88787D01*
G01X300741Y87004D02*
G02X299476Y87247I1J3419D01*
G01X300742Y88279D02*
G02X299948Y88432I1J2144D01*
G01X312638Y87004D02*
X300741D01*
G01X300453Y167375D02*
X322000D01*
G01X300453D02*
X322000D01*
G01X300453Y168650D02*
X304170D01*
G01X300453Y167375D02*
X322000D01*
G01X299427Y169074D02*
G03X300453Y168650I1026J1029D01*
G01X298526Y168170D02*
G03X300453Y167375I1925J1934D01*
G01X299000Y169500D02*
X299427Y169074D01*
G01X298098Y168597D02*
X298526Y168170D01*
G01X291906Y174790D02*
X298098Y168597D01*
G01X294679Y173821D02*
X295793Y172707D01*
G01X291906Y174790D02*
X298098Y168597D01*
G01X290359Y178141D02*
X291473Y177027D01*
G01X300453Y167375D02*
X322000D01*
G01X300453Y168650D02*
X304170D01*
G01X298526Y168170D02*
G03X300453Y167375I1925J1934D01*
G01X299427Y169074D02*
G03X300453Y168650I1026J1029D01*
G01X298098Y168597D02*
X298526Y168170D01*
G01X299000Y169500D02*
X299427Y169074D01*
G01X291906Y174790D02*
X298098Y168597D01*
G01X299000Y169500D02*
X299427Y169074D01*
G01X294679Y173821D02*
X295793Y172707D01*
G01X290359Y178141D02*
X291473Y177027D01*
G01X312639Y88279D02*
X305277D01*
G01X312981Y88347D02*
G02X312639Y88279I-342J824D01*
G01X313418Y87148D02*
G02X312638Y87004I-777J2023D01*
G01X314775Y89117D02*
G02X313424Y87150I-2107J0D01*
G01X313500Y89117D02*
G02X312987Y88349I-831J0D01*
G01X314775Y89117D02*
G02X313424Y87150I-2107J0D01*
G01X313500Y90231D02*
Y89117D01*
G01X314775Y133001D02*
Y89117D01*
G01X313500Y96341D02*
Y94766D01*
G01X314775Y133001D02*
Y89117D01*
G01Y133001D02*
Y89117D01*
G01Y133001D02*
Y89117D01*
G01Y133001D02*
Y89117D01*
G01Y133001D02*
Y89117D01*
G01Y133001D02*
Y89117D01*
G01Y133001D02*
Y89117D01*
G01X312639Y88279D02*
X305277D01*
G01X313418Y87148D02*
G02X312638Y87004I-777J2023D01*
G01X312981Y88347D02*
G02X312639Y88279I-342J824D01*
G01X314775Y89117D02*
G02X313424Y87150I-2107J0D01*
G01X312981Y88347D02*
G02X312639Y88279I-342J824D01*
G01X313500Y89117D02*
G02X312987Y88349I-831J0D01*
G01X314775Y133001D02*
Y89117D01*
G01X313500Y90231D02*
Y89117D01*
G01Y96341D02*
Y94766D01*
G01Y102451D02*
Y100876D01*
G01Y108561D02*
Y106986D01*
G01Y102451D02*
Y100876D01*
G01Y108561D02*
Y106986D01*
G01Y114671D02*
Y113096D01*
G01Y120781D02*
Y119206D01*
G01Y126891D02*
Y125316D01*
G01Y114671D02*
Y113096D01*
G01Y120781D02*
Y119206D01*
G01Y126891D02*
Y125316D01*
G01Y133001D02*
Y131426D01*
G01X313147Y133853D02*
G02X313500Y133001I-852J-852D01*
G01X314049Y134755D02*
G02X314775Y133001I-1754J-1753D01*
G01X312295Y135481D02*
G02X314049Y134755I1J-2480D01*
G01X312295Y134206D02*
G02X313147Y133853I0J-1205D01*
G01X314049Y134755D02*
G02X314775Y133001I-1754J-1753D01*
G01X312295Y135481D02*
G02X314049Y134755I1J-2480D01*
G01X311610Y134206D02*
X312295D01*
G01X305600Y135481D02*
X312295D01*
G01X306500Y134206D02*
X307075D01*
G01X305600Y135481D02*
X312295D01*
G01X313500Y133001D02*
Y131426D01*
G01X314049Y134755D02*
G02X314775Y133001I-1754J-1753D01*
G01X313147Y133853D02*
G02X313500Y133001I-852J-852D01*
G01X312295Y134206D02*
G02X313147Y133853I0J-1205D01*
G01X312295Y135481D02*
G02X314049Y134755I1J-2480D01*
G01X313147Y133853D02*
G02X313500Y133001I-852J-852D01*
G01X312295Y134206D02*
G02X313147Y133853I0J-1205D01*
G01X305600Y135481D02*
X312295D01*
G01X311610Y134206D02*
X312295D01*
G01X306500D02*
X307075D01*
G01X314815Y168650D02*
X316390D01*
G01X308705D02*
X310280D01*
G01X314815D02*
X316390D01*
G01X308705D02*
X310280D01*
M02*
